# S9S_MB_2U (Grand Teton) — schematic netlist excerpt (pin names and nets, part order shuffled) for the footprints in the layout excerpt that follows; sources: Cadence DE-HDL packaged netlist, KiCad conversion of 03242023_DA0F0TMBIJ0_F0T_Motherboard_J_brd_V01_OCP.brd

Q46  MOSFET_NCH_GDS_ESD_PROTECTED  2N7002K IC  pkg SOT23_GDSXC  page 191
  D  = E1S_0_PRSNT
  G  = E1S_0_PRSNT_N
  S  = GND

R1824  Q_RES  10K 1% CHIP  pkg 0402LF  page 155 : A = P3V3_OCP_SFF ; B = IRQ_LVC3_OCP_SFF_WAKE_N

(kicad_pcb
	(version 20260206)
	(generator "pcbnew")
	(generator_version "10.0")
	(general
		(thickness 1.6)
		(legacy_teardrops no)
	)
	(paper "A4")
	(title_block
		(title "03242023_DA0F0TMBIJ0_F0T_Motherboard_J_brd_V01_OCP.brd")
		(comment 1 "Grand Teton / footprints 3544-3545 of 6105")
	)
	(layers
		(0 "F.Cu" signal "TOP")
		(4 "In1.Cu" signal "GND")
		(6 "In2.Cu" signal "IN1")
		(8 "In3.Cu" signal "GND1")
		(10 "In4.Cu" signal "IN2")
		(12 "In5.Cu" signal "GND2")
		(14 "In6.Cu" signal "IN3")
		(16 "In7.Cu" signal "GND3")
		(18 "In8.Cu" signal "VCC")
		(20 "In9.Cu" signal "VCC1")
		(22 "In10.Cu" signal "GND4")
		(24 "In11.Cu" signal "IN4")
		(26 "In12.Cu" signal "GND5")
		(28 "In13.Cu" signal "IN5")
		(30 "In14.Cu" signal "GND6")
		(32 "In15.Cu" signal "IN6")
		(34 "In16.Cu" signal "GND7")
		(2 "B.Cu" signal "BOTTOM")
		(9 "F.Adhes" user "F.Adhesive")
		(11 "B.Adhes" user "B.Adhesive")
		(13 "F.Paste" user "Package Geometry/Pastemask Top")
		(15 "B.Paste" user "Package Geometry/Pastemask Bottom")
		(5 "F.SilkS" user "Ref Des/Silkscreen Top")
		(7 "B.SilkS" user "Ref Des/Silkscreen Bottom")
		(1 "F.Mask" user "Board Geometry/Soldermask Top")
		(3 "B.Mask" user "Board Geometry/Soldermask Bottom")
		(17 "Dwgs.User" user "User.Drawings")
		(19 "Cmts.User" user "User.Comments")
		(21 "Eco1.User" user "User.Eco1")
		(23 "Eco2.User" user "User.Eco2")
		(25 "Edge.Cuts" user "Board Geometry/Outline")
		(27 "Margin" user)
		(31 "F.CrtYd" user "Package Geometry/Place Bound Top")
		(29 "B.CrtYd" user "Package Geometry/Place Bound Bottom")
		(35 "F.Fab" user "Ref Des/Assembly Top")
		(33 "B.Fab" user "Ref Des/Assembly Bottom")
	)
	(footprint ""
		(layer "F.Cu")
		(at 137.176256 -64.694308)
		(property "Reference" "Q46"
			(at -0.3937 2.62763 0)
			(unlocked yes)
			(layer "F.SilkS")
			(effects
				(font
					(size 0.7874 0.5842)
					(thickness 0.1524)
				)
				(justify left)
			)
		)
		(property "Value" ""
			(at 0 0 0)
			(layer "F.Fab")
			(effects
				(font
					(size 1.27 1.27)
				)
			)
		)
		(duplicate_pad_numbers_are_jumpers no)
		(fp_line
			(start -1.603248 -1.500124)
			(end 1.603248 -1.500124)
			(stroke
				(width 0.1524)
				(type default)
			)
			(layer "F.SilkS")
		)
		(fp_line
			(start -1.603248 1.500124)
			(end -1.603248 -1.500124)
			(stroke
				(width 0.1524)
				(type default)
			)
			(layer "F.SilkS")
		)
		(fp_line
			(start 1.603248 -1.500124)
			(end 1.603248 1.500124)
			(stroke
				(width 0.1524)
				(type default)
			)
			(layer "F.SilkS")
		)
		(fp_line
			(start 1.603248 1.500124)
			(end -1.603248 1.500124)
			(stroke
				(width 0.1524)
				(type default)
			)
			(layer "F.SilkS")
		)
		(fp_line
			(start -1.249934 -1.169924)
			(end -1.249934 -0.729996)
			(stroke
				(width 0.1)
				(type default)
			)
			(layer "F.Fab")
		)
		(fp_line
			(start -1.249934 -0.729996)
			(end -0.6985 -0.729996)
			(stroke
				(width 0.1)
				(type default)
			)
			(layer "F.Fab")
		)
		(fp_line
			(start -1.249934 0.729996)
			(end -1.249934 1.169924)
			(stroke
				(width 0.1)
				(type default)
			)
			(layer "F.Fab")
		)
		(fp_line
			(start -1.249934 1.169924)
			(end -0.700024 1.169924)
			(stroke
				(width 0.1)
				(type default)
			)
			(layer "F.Fab")
		)
		(fp_line
			(start -0.700024 -1.500124)
			(end -0.700024 -1.169924)
			(stroke
				(width 0.1)
				(type default)
			)
			(layer "F.Fab")
		)
		(fp_line
			(start -0.700024 -1.169924)
			(end -1.249934 -1.169924)
			(stroke
				(width 0.1)
				(type default)
			)
			(layer "F.Fab")
		)
		(fp_line
			(start -0.700024 1.169924)
			(end -0.700024 1.500124)
			(stroke
				(width 0.1)
				(type default)
			)
			(layer "F.Fab")
		)
		(fp_line
			(start -0.700024 1.500124)
			(end 0.700024 1.500124)
			(stroke
				(width 0.1)
				(type default)
			)
			(layer "F.Fab")
		)
		(fp_line
			(start -0.6985 -0.729996)
			(end -0.6985 0.729996)
			(stroke
				(width 0.1)
				(type default)
			)
			(layer "F.Fab")
		)
		(fp_line
			(start -0.6985 0.729996)
			(end -1.249934 0.729996)
			(stroke
				(width 0.1)
				(type default)
			)
			(layer "F.Fab")
		)
		(fp_line
			(start 0.700024 -1.500124)
			(end -0.700024 -1.500124)
			(stroke
				(width 0.1)
				(type default)
			)
			(layer "F.Fab")
		)
		(fp_line
			(start 0.700024 -0.219964)
			(end 0.700024 -1.500124)
			(stroke
				(width 0.1)
				(type default)
			)
			(layer "F.Fab")
		)
		(fp_line
			(start 0.700024 0.219964)
			(end 1.249934 0.219964)
			(stroke
				(width 0.1)
				(type default)
			)
			(layer "F.Fab")
		)
		(fp_line
			(start 0.700024 1.500124)
			(end 0.700024 0.219964)
			(stroke
				(width 0.1)
				(type default)
			)
			(layer "F.Fab")
		)
		(fp_line
			(start 1.249934 -0.219964)
			(end 0.700024 -0.219964)
			(stroke
				(width 0.1)
				(type default)
			)
			(layer "F.Fab")
		)
		(fp_line
			(start 1.249934 0.219964)
			(end 1.249934 -0.219964)
			(stroke
				(width 0.1)
				(type default)
			)
			(layer "F.Fab")
		)
		(fp_rect
			(start -0.700024 1.500124)
			(end 0.700024 -1.500124)
			(stroke
				(width 0)
				(type default)
			)
			(fill no)
			(layer "F.Fab")
		)
		(pad "D" smd rect
			(at 0.999998 0 270)
			(size 0.8128 0.9144)
			(layers "F.Cu" "F.Mask" "F.Paste")
			(net "E1S_0_PRSNT")
		)
		(pad "G" smd rect
			(at -0.999998 -0.94996 270)
			(size 0.8128 0.9144)
			(layers "F.Cu" "F.Mask" "F.Paste")
			(net "E1S_0_PRSNT_N")
		)
		(pad "S" smd rect
			(at -0.999998 0.94996 270)
			(size 0.8128 0.9144)
			(layers "F.Cu" "F.Mask" "F.Paste")
			(net "GND")
		)
	)
	(footprint ""
		(layer "F.Cu")
		(at 460.1845 -45.693838)
		(property "Reference" "R1824"
			(at 0 0 0)
			(layer "F.SilkS")
			(hide yes)
			(effects
				(font
					(size 1.27 1.27)
				)
			)
		)
		(property "Value" ""
			(at 0 0 0)
			(layer "F.Fab")
			(effects
				(font
					(size 1.27 1.27)
				)
			)
		)
		(duplicate_pad_numbers_are_jumpers no)
		(fp_line
			(start -0.7874 -0.4064)
			(end 0.7874 -0.4064)
			(stroke
				(width 0.1524)
				(type default)
			)
			(layer "F.SilkS")
		)
		(fp_line
			(start -0.7874 0.4064)
			(end -0.7874 -0.4064)
			(stroke
				(width 0.1524)
				(type default)
			)
			(layer "F.SilkS")
		)
		(fp_line
			(start 0.7874 -0.4064)
			(end 0.7874 0.4064)
			(stroke
				(width 0.1524)
				(type default)
			)
			(layer "F.SilkS")
		)
		(fp_line
			(start 0.7874 0.4064)
			(end -0.7874 0.4064)
			(stroke
				(width 0.1524)
				(type default)
			)
			(layer "F.SilkS")
		)
		(fp_line
			(start -0.67945 -0.305054)
			(end -0.12065 -0.305054)
			(stroke
				(width 0.1)
				(type default)
			)
			(layer "F.Fab")
		)
		(fp_line
			(start -0.67945 0.3048)
			(end -0.67945 -0.305054)
			(stroke
				(width 0.1)
				(type default)
			)
			(layer "F.Fab")
		)
		(fp_line
			(start -0.12065 -0.305054)
			(end -0.12065 -0.2794)
			(stroke
				(width 0.1)
				(type default)
			)
			(layer "F.Fab")
		)
		(fp_line
			(start -0.12065 -0.2794)
			(end 0.12065 -0.2794)
			(stroke
				(width 0.1)
				(type default)
			)
			(layer "F.Fab")
		)
		(fp_line
			(start -0.12065 0.2794)
			(end -0.12065 0.3048)
			(stroke
				(width 0.1)
				(type default)
			)
			(layer "F.Fab")
		)
		(fp_line
			(start -0.12065 0.3048)
			(end -0.67945 0.3048)
			(stroke
				(width 0.1)
				(type default)
			)
			(layer "F.Fab")
		)
		(fp_line
			(start 0.120396 0.2794)
			(end -0.12065 0.2794)
			(stroke
				(width 0.1)
				(type default)
			)
			(layer "F.Fab")
		)
		(fp_line
			(start 0.120396 0.3048)
			(end 0.120396 0.2794)
			(stroke
				(width 0.1)
				(type default)
			)
			(layer "F.Fab")
		)
		(fp_line
			(start 0.12065 -0.3048)
			(end 0.67945 -0.3048)
			(stroke
				(width 0.1)
				(type default)
			)
			(layer "F.Fab")
		)
		(fp_line
			(start 0.12065 -0.2794)
			(end 0.12065 -0.3048)
			(stroke
				(width 0.1)
				(type default)
			)
			(layer "F.Fab")
		)
		(fp_line
			(start 0.67945 -0.3048)
			(end 0.67945 0.3048)
			(stroke
				(width 0.1)
				(type default)
			)
			(layer "F.Fab")
		)
		(fp_line
			(start 0.67945 0.3048)
			(end 0.120396 0.3048)
			(stroke
				(width 0.1)
				(type default)
			)
			(layer "F.Fab")
		)
		(pad "1" smd circle
			(at -0.40005 0)
			(size 0 0)
			(layers "F.Cu" "F.Mask" "F.Paste")
			(net "P3V3_OCP_SFF")
		)
		(pad "2" smd circle
			(at 0.40005 0)
			(size 0 0)
			(layers "F.Cu" "F.Mask" "F.Paste")
			(net "IRQ_LVC3_OCP_SFF_WAKE_N")
		)
	)
)
